FILE_TYPE = MULTI_PHYS_TABLE;

PART 'LTC4307CMS8'

{========================================================================================}
:VALUE         | PART_TYPE | MATERIAL | PART_NUMBER      = PART_NUMBER   | JEDEC_TYPE | DESCRIPTION                            | MANUFTR | MANUF_PN            | RD_CMPLS_LVL | CMPLS_LVL | FROM_PJ     | CLASS | DIP_SMD | DATA              | EE_CHECK_LIST | FP_ECN | PSL | LIFECYCLE | CREATOR | STANDARD | CREATEDAY  | STATUS ;
{========================================================================================}
 'LTC4307CMS8' | 'SMLF'    | 'IC'     | 'AL004307000'(!) = 'AL004307000' |'MSOP8'| 'IC OTHER(8P) LTC4307CMS8#TRPBF(MSOP)' | 'LIN'   | 'LTC4307CMS8#TRPBF' | ''           | 'EP_Tmp'  | 'LU1-EASON' | 'IC'  | ''      | 'LIN_LTC4307.pdf' | ''            | ''     | ''  | ''        | ''      | ''       | '20111202' | ''    
 'LTC4307CMS8' | 'SMLF'    | 'EMPTY'  | 'AL004307000'(!) = 'AL004307000' |'MSOP8'| 'IC OTHER(8P) LTC4307CMS8#TRPBF(MSOP)' | 'LIN'   | 'LTC4307CMS8#TRPBF' | ''           | 'EP_Tmp'  | 'LU1-EASON' | 'IC'  | ''      | 'LIN_LTC4307.pdf' | ''            | ''     | ''  | ''        | ''      | ''       | '20111202' | ''    

END_PART

END.

